# S9S_MB_2U (Grand Teton) — schematic netlist excerpt (pin names and nets, part order shuffled) for the footprints in the layout excerpt that follows; sources: Cadence DE-HDL packaged netlist, KiCad conversion of 03242023_DA0F0TMBIJ0_F0T_Motherboard_J_brd_V01_OCP.brd

C1320  Q_CAP  0.1UF 25V 10% X7R  pkg 0402  page 214 : A = P3V3_AUX ; B = GND
R3704  Q_RES  1K 1% CHIP  pkg 0402LF  page 233 : A = PCA9548_PCIE0_ADDR2 ; B = GND

(kicad_pcb
	(version 20260206)
	(generator "pcbnew")
	(generator_version "10.0")
	(general
		(thickness 1.6)
		(legacy_teardrops no)
	)
	(paper "A4")
	(title_block
		(title "03242023_DA0F0TMBIJ0_F0T_Motherboard_J_brd_V01_OCP.brd")
		(comment 1 "Grand Teton / footprints 1273-1274 of 6105")
	)
	(layers
		(0 "F.Cu" signal "TOP")
		(4 "In1.Cu" signal "GND")
		(6 "In2.Cu" signal "IN1")
		(8 "In3.Cu" signal "GND1")
		(10 "In4.Cu" signal "IN2")
		(12 "In5.Cu" signal "GND2")
		(14 "In6.Cu" signal "IN3")
		(16 "In7.Cu" signal "GND3")
		(18 "In8.Cu" signal "VCC")
		(20 "In9.Cu" signal "VCC1")
		(22 "In10.Cu" signal "GND4")
		(24 "In11.Cu" signal "IN4")
		(26 "In12.Cu" signal "GND5")
		(28 "In13.Cu" signal "IN5")
		(30 "In14.Cu" signal "GND6")
		(32 "In15.Cu" signal "IN6")
		(34 "In16.Cu" signal "GND7")
		(2 "B.Cu" signal "BOTTOM")
		(9 "F.Adhes" user "F.Adhesive")
		(11 "B.Adhes" user "B.Adhesive")
		(13 "F.Paste" user "Package Geometry/Pastemask Top")
		(15 "B.Paste" user "Package Geometry/Pastemask Bottom")
		(5 "F.SilkS" user "Ref Des/Silkscreen Top")
		(7 "B.SilkS" user "Ref Des/Silkscreen Bottom")
		(1 "F.Mask" user "Board Geometry/Soldermask Top")
		(3 "B.Mask" user "Board Geometry/Soldermask Bottom")
		(17 "Dwgs.User" user "User.Drawings")
		(19 "Cmts.User" user "User.Comments")
		(21 "Eco1.User" user "User.Eco1")
		(23 "Eco2.User" user "User.Eco2")
		(25 "Edge.Cuts" user "Board Geometry/Outline")
		(27 "Margin" user)
		(31 "F.CrtYd" user "Package Geometry/Place Bound Top")
		(29 "B.CrtYd" user "Package Geometry/Place Bound Bottom")
		(35 "F.Fab" user "Ref Des/Assembly Top")
		(33 "B.Fab" user "Ref Des/Assembly Bottom")
	)
	(footprint ""
		(layer "F.Cu")
		(at 68.085716 -112.70869)
		(property "Reference" "R3704"
			(at 0 0 0)
			(layer "F.SilkS")
			(hide yes)
			(effects
				(font
					(size 1.27 1.27)
				)
			)
		)
		(property "Value" ""
			(at 0 0 0)
			(layer "F.Fab")
			(effects
				(font
					(size 1.27 1.27)
				)
			)
		)
		(duplicate_pad_numbers_are_jumpers no)
		(fp_line
			(start -0.7874 -0.4064)
			(end 0.7874 -0.4064)
			(stroke
				(width 0.1524)
				(type default)
			)
			(layer "F.SilkS")
		)
		(fp_line
			(start -0.7874 0.4064)
			(end -0.7874 -0.4064)
			(stroke
				(width 0.1524)
				(type default)
			)
			(layer "F.SilkS")
		)
		(fp_line
			(start 0.7874 -0.4064)
			(end 0.7874 0.4064)
			(stroke
				(width 0.1524)
				(type default)
			)
			(layer "F.SilkS")
		)
		(fp_line
			(start 0.7874 0.4064)
			(end -0.7874 0.4064)
			(stroke
				(width 0.1524)
				(type default)
			)
			(layer "F.SilkS")
		)
		(fp_line
			(start -0.67945 -0.305054)
			(end -0.12065 -0.305054)
			(stroke
				(width 0.1)
				(type default)
			)
			(layer "F.Fab")
		)
		(fp_line
			(start -0.67945 0.3048)
			(end -0.67945 -0.305054)
			(stroke
				(width 0.1)
				(type default)
			)
			(layer "F.Fab")
		)
		(fp_line
			(start -0.12065 -0.305054)
			(end -0.12065 -0.2794)
			(stroke
				(width 0.1)
				(type default)
			)
			(layer "F.Fab")
		)
		(fp_line
			(start -0.12065 -0.2794)
			(end 0.12065 -0.2794)
			(stroke
				(width 0.1)
				(type default)
			)
			(layer "F.Fab")
		)
		(fp_line
			(start -0.12065 0.2794)
			(end -0.12065 0.3048)
			(stroke
				(width 0.1)
				(type default)
			)
			(layer "F.Fab")
		)
		(fp_line
			(start -0.12065 0.3048)
			(end -0.67945 0.3048)
			(stroke
				(width 0.1)
				(type default)
			)
			(layer "F.Fab")
		)
		(fp_line
			(start 0.120396 0.2794)
			(end -0.12065 0.2794)
			(stroke
				(width 0.1)
				(type default)
			)
			(layer "F.Fab")
		)
		(fp_line
			(start 0.120396 0.3048)
			(end 0.120396 0.2794)
			(stroke
				(width 0.1)
				(type default)
			)
			(layer "F.Fab")
		)
		(fp_line
			(start 0.12065 -0.3048)
			(end 0.67945 -0.3048)
			(stroke
				(width 0.1)
				(type default)
			)
			(layer "F.Fab")
		)
		(fp_line
			(start 0.12065 -0.2794)
			(end 0.12065 -0.3048)
			(stroke
				(width 0.1)
				(type default)
			)
			(layer "F.Fab")
		)
		(fp_line
			(start 0.67945 -0.3048)
			(end 0.67945 0.3048)
			(stroke
				(width 0.1)
				(type default)
			)
			(layer "F.Fab")
		)
		(fp_line
			(start 0.67945 0.3048)
			(end 0.120396 0.3048)
			(stroke
				(width 0.1)
				(type default)
			)
			(layer "F.Fab")
		)
		(pad "1" smd circle
			(at -0.40005 0)
			(size 0 0)
			(layers "F.Cu" "F.Mask" "F.Paste")
			(net "PCA9548_PCIE0_ADDR2")
		)
		(pad "2" smd circle
			(at 0.40005 0)
			(size 0 0)
			(layers "F.Cu" "F.Mask" "F.Paste")
			(net "GND")
		)
	)
	(footprint ""
		(layer "F.Cu")
		(at 197.41388 -111.724948 -90)
		(property "Reference" "C1320"
			(at 0 0 270)
			(layer "F.SilkS")
			(hide yes)
			(effects
				(font
					(size 1.27 1.27)
				)
			)
		)
		(property "Value" ""
			(at 0 0 270)
			(layer "F.Fab")
			(effects
				(font
					(size 1.27 1.27)
				)
			)
		)
		(duplicate_pad_numbers_are_jumpers no)
		(fp_line
			(start -0.7874 0.4064)
			(end -0.7874 -0.4064)
			(stroke
				(width 0.1524)
				(type default)
			)
			(layer "F.SilkS")
		)
		(fp_line
			(start 0.7874 0.4064)
			(end -0.7874 0.4064)
			(stroke
				(width 0.1524)
				(type default)
			)
			(layer "F.SilkS")
		)
		(fp_line
			(start -0.7874 -0.4064)
			(end 0.7874 -0.4064)
			(stroke
				(width 0.1524)
				(type default)
			)
			(layer "F.SilkS")
		)
		(fp_line
			(start 0.7874 -0.4064)
			(end 0.7874 0.4064)
			(stroke
				(width 0.1524)
				(type default)
			)
			(layer "F.SilkS")
		)
		(fp_line
			(start -0.67945 0.3048)
			(end -0.67945 -0.305054)
			(stroke
				(width 0.1)
				(type default)
			)
			(layer "F.Fab")
		)
		(fp_line
			(start -0.12065 0.3048)
			(end -0.67945 0.3048)
			(stroke
				(width 0.1)
				(type default)
			)
			(layer "F.Fab")
		)
		(fp_line
			(start 0.120396 0.3048)
			(end 0.120396 0.2794)
			(stroke
				(width 0.1)
				(type default)
			)
			(layer "F.Fab")
		)
		(fp_line
			(start 0.67945 0.3048)
			(end 0.120396 0.3048)
			(stroke
				(width 0.1)
				(type default)
			)
			(layer "F.Fab")
		)
		(fp_line
			(start -0.12065 0.2794)
			(end -0.12065 0.3048)
			(stroke
				(width 0.1)
				(type default)
			)
			(layer "F.Fab")
		)
		(fp_line
			(start 0.120396 0.2794)
			(end -0.12065 0.2794)
			(stroke
				(width 0.1)
				(type default)
			)
			(layer "F.Fab")
		)
		(fp_line
			(start -0.12065 -0.2794)
			(end 0.12065 -0.2794)
			(stroke
				(width 0.1)
				(type default)
			)
			(layer "F.Fab")
		)
		(fp_line
			(start 0.12065 -0.2794)
			(end 0.12065 -0.3048)
			(stroke
				(width 0.1)
				(type default)
			)
			(layer "F.Fab")
		)
		(fp_line
			(start 0.12065 -0.3048)
			(end 0.67945 -0.3048)
			(stroke
				(width 0.1)
				(type default)
			)
			(layer "F.Fab")
		)
		(fp_line
			(start 0.67945 -0.3048)
			(end 0.67945 0.3048)
			(stroke
				(width 0.1)
				(type default)
			)
			(layer "F.Fab")
		)
		(fp_line
			(start -0.67945 -0.305054)
			(end -0.12065 -0.305054)
			(stroke
				(width 0.1)
				(type default)
			)
			(layer "F.Fab")
		)
		(fp_line
			(start -0.12065 -0.305054)
			(end -0.12065 -0.2794)
			(stroke
				(width 0.1)
				(type default)
			)
			(layer "F.Fab")
		)
		(pad "1" smd circle
			(at -0.40005 0 270)
			(size 0 0)
			(layers "F.Cu" "F.Mask" "F.Paste")
			(net "P3V3_AUX")
		)
		(pad "2" smd circle
			(at 0.40005 0 270)
			(size 0 0)
			(layers "F.Cu" "F.Mask" "F.Paste")
			(net "GND")
		)
	)
)
